# SCM (Grand Teton) — schematic netlist excerpt (pin names and nets, part order shuffled) for the footprints in the layout excerpt that follows; sources: Cadence DE-HDL packaged netlist, KiCad conversion of 12092022_DA0F0TMDCD0_F0T_Management_Board_D_brd_V3_OCP.brd

R62  Q_RES  4.7K 1% CHIP  pkg 0402LF  page 12 : A = P3V3_AUX ; B = FM_PCH_BMC_THERMTRIP_N
R378  Q_RES  20K 1% CHIP  pkg 0402LF  page 28 : A = USB_OC0_ILIM ; B = GND

(kicad_pcb
	(version 20260206)
	(generator "pcbnew")
	(generator_version "10.0")
	(general
		(thickness 1.6)
		(legacy_teardrops no)
	)
	(paper "A4")
	(title_block
		(title "12092022_DA0F0TMDCD0_F0T_Management_Board_D_brd_V3_OCP.brd")
		(comment 1 "Grand Teton / footprints 663-664 of 1440")
	)
	(layers
		(0 "F.Cu" signal "TOP")
		(4 "In1.Cu" signal "GND")
		(6 "In2.Cu" signal "IN1")
		(8 "In3.Cu" signal "GND1")
		(10 "In4.Cu" signal "IN2")
		(12 "In5.Cu" signal "VCC")
		(14 "In6.Cu" signal "VCC1")
		(16 "In7.Cu" signal "IN3")
		(18 "In8.Cu" signal "GND2")
		(20 "In9.Cu" signal "IN4")
		(22 "In10.Cu" signal "GND3")
		(2 "B.Cu" signal "BOTTOM")
		(9 "F.Adhes" user "F.Adhesive")
		(11 "B.Adhes" user "B.Adhesive")
		(13 "F.Paste" user "Package Geometry/Pastemask Top")
		(15 "B.Paste" user "Package Geometry/Pastemask Bottom")
		(5 "F.SilkS" user "Ref Des/Silkscreen Top")
		(7 "B.SilkS" user "Ref Des/Silkscreen Bottom")
		(1 "F.Mask" user "Board Geometry/Soldermask Top")
		(3 "B.Mask" user "Board Geometry/Soldermask Bottom")
		(17 "Dwgs.User" user "User.Drawings")
		(19 "Cmts.User" user "User.Comments")
		(21 "Eco1.User" user "User.Eco1")
		(23 "Eco2.User" user "User.Eco2")
		(25 "Edge.Cuts" user "Board Geometry/Outline")
		(27 "Margin" user)
		(31 "F.CrtYd" user "Package Geometry/Place Bound Top")
		(29 "B.CrtYd" user "Package Geometry/Place Bound Bottom")
		(35 "F.Fab" user "Ref Des/Assembly Top")
		(33 "B.Fab" user "Ref Des/Assembly Bottom")
	)
	(footprint ""
		(layer "F.Cu")
		(at 43.848528 -30.867604 90)
		(property "Reference" "R62"
			(at 0 0 90)
			(layer "F.SilkS")
			(hide yes)
			(effects
				(font
					(size 1.27 1.27)
				)
			)
		)
		(property "Value" ""
			(at 0 0 90)
			(layer "F.Fab")
			(effects
				(font
					(size 1.27 1.27)
				)
			)
		)
		(duplicate_pad_numbers_are_jumpers no)
		(fp_line
			(start 0.7874 -0.4064)
			(end 0.7874 0.4064)
			(stroke
				(width 0.1524)
				(type default)
			)
			(layer "F.SilkS")
		)
		(fp_line
			(start -0.7874 -0.4064)
			(end 0.7874 -0.4064)
			(stroke
				(width 0.1524)
				(type default)
			)
			(layer "F.SilkS")
		)
		(fp_line
			(start 0.7874 0.4064)
			(end -0.7874 0.4064)
			(stroke
				(width 0.1524)
				(type default)
			)
			(layer "F.SilkS")
		)
		(fp_line
			(start -0.7874 0.4064)
			(end -0.7874 -0.4064)
			(stroke
				(width 0.1524)
				(type default)
			)
			(layer "F.SilkS")
		)
		(fp_line
			(start -0.12065 -0.305054)
			(end -0.12065 -0.2794)
			(stroke
				(width 0.1)
				(type default)
			)
			(layer "F.Fab")
		)
		(fp_line
			(start -0.67945 -0.305054)
			(end -0.12065 -0.305054)
			(stroke
				(width 0.1)
				(type default)
			)
			(layer "F.Fab")
		)
		(fp_line
			(start 0.67945 -0.3048)
			(end 0.67945 0.3048)
			(stroke
				(width 0.1)
				(type default)
			)
			(layer "F.Fab")
		)
		(fp_line
			(start 0.12065 -0.3048)
			(end 0.67945 -0.3048)
			(stroke
				(width 0.1)
				(type default)
			)
			(layer "F.Fab")
		)
		(fp_line
			(start 0.12065 -0.2794)
			(end 0.12065 -0.3048)
			(stroke
				(width 0.1)
				(type default)
			)
			(layer "F.Fab")
		)
		(fp_line
			(start -0.12065 -0.2794)
			(end 0.12065 -0.2794)
			(stroke
				(width 0.1)
				(type default)
			)
			(layer "F.Fab")
		)
		(fp_line
			(start 0.120396 0.2794)
			(end -0.12065 0.2794)
			(stroke
				(width 0.1)
				(type default)
			)
			(layer "F.Fab")
		)
		(fp_line
			(start -0.12065 0.2794)
			(end -0.12065 0.3048)
			(stroke
				(width 0.1)
				(type default)
			)
			(layer "F.Fab")
		)
		(fp_line
			(start 0.67945 0.3048)
			(end 0.120396 0.3048)
			(stroke
				(width 0.1)
				(type default)
			)
			(layer "F.Fab")
		)
		(fp_line
			(start 0.120396 0.3048)
			(end 0.120396 0.2794)
			(stroke
				(width 0.1)
				(type default)
			)
			(layer "F.Fab")
		)
		(fp_line
			(start -0.12065 0.3048)
			(end -0.67945 0.3048)
			(stroke
				(width 0.1)
				(type default)
			)
			(layer "F.Fab")
		)
		(fp_line
			(start -0.67945 0.3048)
			(end -0.67945 -0.305054)
			(stroke
				(width 0.1)
				(type default)
			)
			(layer "F.Fab")
		)
		(pad "1" smd circle
			(at -0.40005 0 90)
			(size 0 0)
			(layers "F.Cu" "F.Mask" "F.Paste")
			(net "P3V3_AUX")
		)
		(pad "2" smd circle
			(at 0.40005 0 90)
			(size 0 0)
			(layers "F.Cu" "F.Mask" "F.Paste")
			(net "FM_PCH_BMC_THERMTRIP_N")
		)
	)
	(footprint ""
		(layer "F.Cu")
		(at 46.863 -22.352 180)
		(property "Reference" "R378"
			(at 0 0 180)
			(layer "F.SilkS")
			(hide yes)
			(effects
				(font
					(size 1.27 1.27)
				)
			)
		)
		(property "Value" ""
			(at 0 0 180)
			(layer "F.Fab")
			(effects
				(font
					(size 1.27 1.27)
				)
			)
		)
		(duplicate_pad_numbers_are_jumpers no)
		(fp_line
			(start 0.7874 0.4064)
			(end -0.7874 0.4064)
			(stroke
				(width 0.1524)
				(type default)
			)
			(layer "F.SilkS")
		)
		(fp_line
			(start 0.7874 -0.4064)
			(end 0.7874 0.4064)
			(stroke
				(width 0.1524)
				(type default)
			)
			(layer "F.SilkS")
		)
		(fp_line
			(start -0.7874 0.4064)
			(end -0.7874 -0.4064)
			(stroke
				(width 0.1524)
				(type default)
			)
			(layer "F.SilkS")
		)
		(fp_line
			(start -0.7874 -0.4064)
			(end 0.7874 -0.4064)
			(stroke
				(width 0.1524)
				(type default)
			)
			(layer "F.SilkS")
		)
		(fp_line
			(start 0.67945 0.3048)
			(end 0.120396 0.3048)
			(stroke
				(width 0.1)
				(type default)
			)
			(layer "F.Fab")
		)
		(fp_line
			(start 0.67945 -0.3048)
			(end 0.67945 0.3048)
			(stroke
				(width 0.1)
				(type default)
			)
			(layer "F.Fab")
		)
		(fp_line
			(start 0.12065 -0.2794)
			(end 0.12065 -0.3048)
			(stroke
				(width 0.1)
				(type default)
			)
			(layer "F.Fab")
		)
		(fp_line
			(start 0.12065 -0.3048)
			(end 0.67945 -0.3048)
			(stroke
				(width 0.1)
				(type default)
			)
			(layer "F.Fab")
		)
		(fp_line
			(start 0.120396 0.3048)
			(end 0.120396 0.2794)
			(stroke
				(width 0.1)
				(type default)
			)
			(layer "F.Fab")
		)
		(fp_line
			(start 0.120396 0.2794)
			(end -0.12065 0.2794)
			(stroke
				(width 0.1)
				(type default)
			)
			(layer "F.Fab")
		)
		(fp_line
			(start -0.12065 0.3048)
			(end -0.67945 0.3048)
			(stroke
				(width 0.1)
				(type default)
			)
			(layer "F.Fab")
		)
		(fp_line
			(start -0.12065 0.2794)
			(end -0.12065 0.3048)
			(stroke
				(width 0.1)
				(type default)
			)
			(layer "F.Fab")
		)
		(fp_line
			(start -0.12065 -0.2794)
			(end 0.12065 -0.2794)
			(stroke
				(width 0.1)
				(type default)
			)
			(layer "F.Fab")
		)
		(fp_line
			(start -0.12065 -0.305054)
			(end -0.12065 -0.2794)
			(stroke
				(width 0.1)
				(type default)
			)
			(layer "F.Fab")
		)
		(fp_line
			(start -0.67945 0.3048)
			(end -0.67945 -0.305054)
			(stroke
				(width 0.1)
				(type default)
			)
			(layer "F.Fab")
		)
		(fp_line
			(start -0.67945 -0.305054)
			(end -0.12065 -0.305054)
			(stroke
				(width 0.1)
				(type default)
			)
			(layer "F.Fab")
		)
		(pad "1" smd circle
			(at -0.40005 0 180)
			(size 0 0)
			(layers "F.Cu" "F.Mask" "F.Paste")
			(net "USB_OC0_ILIM")
		)
		(pad "2" smd circle
			(at 0.40005 0 180)
			(size 0 0)
			(layers "F.Cu" "F.Mask" "F.Paste")
			(net "GND")
		)
	)
)
